# S9S_MB_2U (Grand Teton) — schematic netlist excerpt (pin names and nets, part order shuffled) for the footprints in the layout excerpt that follows; sources: Cadence DE-HDL packaged netlist, KiCad conversion of 03242023_DA0F0TMBIJ0_F0T_Motherboard_J_brd_V01_OCP.brd

R4615  Q_RES  0 5% EMPTY  pkg 0402LF  page 164 : A = OCP_V3_2_P3V3_PWRGD ; B = HP_OCP_V3_2_RST_R
D86  Q_LED  IC  pkg SMLF  page 254 : A = LED_PWRGD_PVCCIN_CPU1 ; C = LED_PWRGD_PVCCIN_CPU1_D

(kicad_pcb
	(version 20260206)
	(generator "pcbnew")
	(generator_version "10.0")
	(general
		(thickness 1.6)
		(legacy_teardrops no)
	)
	(paper "A4")
	(title_block
		(title "03242023_DA0F0TMBIJ0_F0T_Motherboard_J_brd_V01_OCP.brd")
		(comment 1 "Grand Teton / footprints 3703-3704 of 6105")
	)
	(layers
		(0 "F.Cu" signal "TOP")
		(4 "In1.Cu" signal "GND")
		(6 "In2.Cu" signal "IN1")
		(8 "In3.Cu" signal "GND1")
		(10 "In4.Cu" signal "IN2")
		(12 "In5.Cu" signal "GND2")
		(14 "In6.Cu" signal "IN3")
		(16 "In7.Cu" signal "GND3")
		(18 "In8.Cu" signal "VCC")
		(20 "In9.Cu" signal "VCC1")
		(22 "In10.Cu" signal "GND4")
		(24 "In11.Cu" signal "IN4")
		(26 "In12.Cu" signal "GND5")
		(28 "In13.Cu" signal "IN5")
		(30 "In14.Cu" signal "GND6")
		(32 "In15.Cu" signal "IN6")
		(34 "In16.Cu" signal "GND7")
		(2 "B.Cu" signal "BOTTOM")
		(9 "F.Adhes" user "F.Adhesive")
		(11 "B.Adhes" user "B.Adhesive")
		(13 "F.Paste" user "Package Geometry/Pastemask Top")
		(15 "B.Paste" user "Package Geometry/Pastemask Bottom")
		(5 "F.SilkS" user "Ref Des/Silkscreen Top")
		(7 "B.SilkS" user "Ref Des/Silkscreen Bottom")
		(1 "F.Mask" user "Board Geometry/Soldermask Top")
		(3 "B.Mask" user "Board Geometry/Soldermask Bottom")
		(17 "Dwgs.User" user "User.Drawings")
		(19 "Cmts.User" user "User.Comments")
		(21 "Eco1.User" user "User.Eco1")
		(23 "Eco2.User" user "User.Eco2")
		(25 "Edge.Cuts" user "Board Geometry/Outline")
		(27 "Margin" user)
		(31 "F.CrtYd" user "Package Geometry/Place Bound Top")
		(29 "B.CrtYd" user "Package Geometry/Place Bound Bottom")
		(35 "F.Fab" user "Ref Des/Assembly Top")
		(33 "B.Fab" user "Ref Des/Assembly Bottom")
	)
	(footprint ""
		(layer "F.Cu")
		(at 96.983296 -70.78599)
		(property "Reference" "D86"
			(at -48.854106 50.178462 90)
			(unlocked yes)
			(layer "F.SilkS")
			(effects
				(font
					(size 0.635 0.4064)
					(thickness 0.1524)
				)
				(justify left)
			)
		)
		(property "Value" ""
			(at 0 0 0)
			(layer "F.Fab")
			(effects
				(font
					(size 1.27 1.27)
				)
			)
		)
		(duplicate_pad_numbers_are_jumpers no)
		(fp_line
			(start -0.90678 0.4826)
			(end -0.90678 -0.4699)
			(stroke
				(width 0.1524)
				(type default)
			)
			(layer "F.SilkS")
		)
		(fp_line
			(start -0.89408 -0.4826)
			(end 0.90678 -0.4826)
			(stroke
				(width 0.1524)
				(type default)
			)
			(layer "F.SilkS")
		)
		(fp_line
			(start -0.79248 -0.4826)
			(end 1.03378 -0.4826)
			(stroke
				(width 0.1524)
				(type default)
			)
			(layer "F.SilkS")
		)
		(fp_line
			(start -0.64008 -0.4826)
			(end 1.16078 -0.4826)
			(stroke
				(width 0.1524)
				(type default)
			)
			(layer "F.SilkS")
		)
		(fp_line
			(start 0.90678 -0.4826)
			(end 0.90678 0.4826)
			(stroke
				(width 0.1524)
				(type default)
			)
			(layer "F.SilkS")
		)
		(fp_line
			(start 0.90678 0.4826)
			(end -0.90678 0.4826)
			(stroke
				(width 0.1524)
				(type default)
			)
			(layer "F.SilkS")
		)
		(fp_line
			(start 1.03378 -0.4826)
			(end 1.03378 0.4826)
			(stroke
				(width 0.1524)
				(type default)
			)
			(layer "F.SilkS")
		)
		(fp_line
			(start 1.03378 0.4826)
			(end -0.79248 0.4826)
			(stroke
				(width 0.1524)
				(type default)
			)
			(layer "F.SilkS")
		)
		(fp_line
			(start 1.16078 -0.4826)
			(end 1.16078 0.4826)
			(stroke
				(width 0.1524)
				(type default)
			)
			(layer "F.SilkS")
		)
		(fp_line
			(start 1.16078 0.4826)
			(end -0.64008 0.4826)
			(stroke
				(width 0.1524)
				(type default)
			)
			(layer "F.SilkS")
		)
		(fp_line
			(start -0.499872 -0.249936)
			(end 0.499872 -0.249936)
			(stroke
				(width 0.1)
				(type default)
			)
			(layer "F.Fab")
		)
		(fp_line
			(start -0.499872 0.249936)
			(end -0.499872 -0.249936)
			(stroke
				(width 0.1)
				(type default)
			)
			(layer "F.Fab")
		)
		(fp_line
			(start 0.499872 -0.249936)
			(end 0.499872 0.249936)
			(stroke
				(width 0.1)
				(type default)
			)
			(layer "F.Fab")
		)
		(fp_line
			(start 0.499872 0.249936)
			(end -0.499872 0.249936)
			(stroke
				(width 0.1)
				(type default)
			)
			(layer "F.Fab")
		)
		(pad "A" smd rect
			(at -0.47498 0)
			(size 0.6096 0.7112)
			(layers "F.Cu" "F.Mask" "F.Paste")
			(net "LED_PWRGD_PVCCIN_CPU1")
		)
		(pad "C" smd rect
			(at 0.47498 0)
			(size 0.6096 0.7112)
			(layers "F.Cu" "F.Mask" "F.Paste")
			(net "LED_PWRGD_PVCCIN_CPU1_D")
		)
	)
	(footprint ""
		(layer "F.Cu")
		(at 83.4898 -35.651948 90)
		(property "Reference" "R4615"
			(at 0 0 90)
			(layer "F.SilkS")
			(hide yes)
			(effects
				(font
					(size 1.27 1.27)
				)
			)
		)
		(property "Value" ""
			(at 0 0 90)
			(layer "F.Fab")
			(effects
				(font
					(size 1.27 1.27)
				)
			)
		)
		(duplicate_pad_numbers_are_jumpers no)
		(fp_line
			(start 0.7874 -0.4064)
			(end 0.7874 0.4064)
			(stroke
				(width 0.1524)
				(type default)
			)
			(layer "F.SilkS")
		)
		(fp_line
			(start -0.7874 -0.4064)
			(end 0.7874 -0.4064)
			(stroke
				(width 0.1524)
				(type default)
			)
			(layer "F.SilkS")
		)
		(fp_line
			(start 0.7874 0.4064)
			(end -0.7874 0.4064)
			(stroke
				(width 0.1524)
				(type default)
			)
			(layer "F.SilkS")
		)
		(fp_line
			(start -0.7874 0.4064)
			(end -0.7874 -0.4064)
			(stroke
				(width 0.1524)
				(type default)
			)
			(layer "F.SilkS")
		)
		(fp_line
			(start -0.12065 -0.305054)
			(end -0.12065 -0.2794)
			(stroke
				(width 0.1)
				(type default)
			)
			(layer "F.Fab")
		)
		(fp_line
			(start -0.67945 -0.305054)
			(end -0.12065 -0.305054)
			(stroke
				(width 0.1)
				(type default)
			)
			(layer "F.Fab")
		)
		(fp_line
			(start 0.67945 -0.3048)
			(end 0.67945 0.3048)
			(stroke
				(width 0.1)
				(type default)
			)
			(layer "F.Fab")
		)
		(fp_line
			(start 0.12065 -0.3048)
			(end 0.67945 -0.3048)
			(stroke
				(width 0.1)
				(type default)
			)
			(layer "F.Fab")
		)
		(fp_line
			(start 0.12065 -0.2794)
			(end 0.12065 -0.3048)
			(stroke
				(width 0.1)
				(type default)
			)
			(layer "F.Fab")
		)
		(fp_line
			(start -0.12065 -0.2794)
			(end 0.12065 -0.2794)
			(stroke
				(width 0.1)
				(type default)
			)
			(layer "F.Fab")
		)
		(fp_line
			(start 0.120396 0.2794)
			(end -0.12065 0.2794)
			(stroke
				(width 0.1)
				(type default)
			)
			(layer "F.Fab")
		)
		(fp_line
			(start -0.12065 0.2794)
			(end -0.12065 0.3048)
			(stroke
				(width 0.1)
				(type default)
			)
			(layer "F.Fab")
		)
		(fp_line
			(start 0.67945 0.3048)
			(end 0.120396 0.3048)
			(stroke
				(width 0.1)
				(type default)
			)
			(layer "F.Fab")
		)
		(fp_line
			(start 0.120396 0.3048)
			(end 0.120396 0.2794)
			(stroke
				(width 0.1)
				(type default)
			)
			(layer "F.Fab")
		)
		(fp_line
			(start -0.12065 0.3048)
			(end -0.67945 0.3048)
			(stroke
				(width 0.1)
				(type default)
			)
			(layer "F.Fab")
		)
		(fp_line
			(start -0.67945 0.3048)
			(end -0.67945 -0.305054)
			(stroke
				(width 0.1)
				(type default)
			)
			(layer "F.Fab")
		)
		(pad "1" smd circle
			(at -0.40005 0 90)
			(size 0 0)
			(layers "F.Cu" "F.Mask" "F.Paste")
			(net "OCP_V3_2_P3V3_PWRGD")
		)
		(pad "2" smd circle
			(at 0.40005 0 90)
			(size 0 0)
			(layers "F.Cu" "F.Mask" "F.Paste")
			(net "HP_OCP_V3_2_RST_R")
		)
	)
)
